# SCM (Grand Teton) — schematic netlist excerpt (pin names and nets, part order shuffled) for the footprints in the layout excerpt that follows; sources: Cadence DE-HDL packaged netlist, KiCad conversion of 12092022_DA0F0TMDCD0_F0T_Management_Board_D_brd_V3_OCP.brd

R124  Q_RES  2K 1% CHIP  pkg 0402LF  page 22 : A = P3V3_AUX ; B = RST_BMC_SRST_BUF_R_N
R823  Q_RES  100K 1% CHIP  pkg 0402LF  page 11 : A = GND ; B = FM_VIRTUAL_RESEAT

(kicad_pcb
	(version 20260206)
	(generator "pcbnew")
	(generator_version "10.0")
	(general
		(thickness 1.6)
		(legacy_teardrops no)
	)
	(paper "A4")
	(title_block
		(title "12092022_DA0F0TMDCD0_F0T_Management_Board_D_brd_V3_OCP.brd")
		(comment 1 "Grand Teton / footprints 565-566 of 1440")
	)
	(layers
		(0 "F.Cu" signal "TOP")
		(4 "In1.Cu" signal "GND")
		(6 "In2.Cu" signal "IN1")
		(8 "In3.Cu" signal "GND1")
		(10 "In4.Cu" signal "IN2")
		(12 "In5.Cu" signal "VCC")
		(14 "In6.Cu" signal "VCC1")
		(16 "In7.Cu" signal "IN3")
		(18 "In8.Cu" signal "GND2")
		(20 "In9.Cu" signal "IN4")
		(22 "In10.Cu" signal "GND3")
		(2 "B.Cu" signal "BOTTOM")
		(9 "F.Adhes" user "F.Adhesive")
		(11 "B.Adhes" user "B.Adhesive")
		(13 "F.Paste" user "Package Geometry/Pastemask Top")
		(15 "B.Paste" user "Package Geometry/Pastemask Bottom")
		(5 "F.SilkS" user "Ref Des/Silkscreen Top")
		(7 "B.SilkS" user "Ref Des/Silkscreen Bottom")
		(1 "F.Mask" user "Board Geometry/Soldermask Top")
		(3 "B.Mask" user "Board Geometry/Soldermask Bottom")
		(17 "Dwgs.User" user "User.Drawings")
		(19 "Cmts.User" user "User.Comments")
		(21 "Eco1.User" user "User.Eco1")
		(23 "Eco2.User" user "User.Eco2")
		(25 "Edge.Cuts" user "Board Geometry/Outline")
		(27 "Margin" user)
		(31 "F.CrtYd" user "Package Geometry/Place Bound Top")
		(29 "B.CrtYd" user "Package Geometry/Place Bound Bottom")
		(35 "F.Fab" user "Ref Des/Assembly Top")
		(33 "B.Fab" user "Ref Des/Assembly Bottom")
	)
	(footprint ""
		(layer "F.Cu")
		(at 10.3632 -107.95 -90)
		(property "Reference" "R124"
			(at 0 0 270)
			(layer "F.SilkS")
			(hide yes)
			(effects
				(font
					(size 1.27 1.27)
				)
			)
		)
		(property "Value" ""
			(at 0 0 270)
			(layer "F.Fab")
			(effects
				(font
					(size 1.27 1.27)
				)
			)
		)
		(duplicate_pad_numbers_are_jumpers no)
		(fp_line
			(start -0.7874 0.4064)
			(end -0.7874 -0.4064)
			(stroke
				(width 0.1524)
				(type default)
			)
			(layer "F.SilkS")
		)
		(fp_line
			(start 0.7874 0.4064)
			(end -0.7874 0.4064)
			(stroke
				(width 0.1524)
				(type default)
			)
			(layer "F.SilkS")
		)
		(fp_line
			(start -0.7874 -0.4064)
			(end 0.7874 -0.4064)
			(stroke
				(width 0.1524)
				(type default)
			)
			(layer "F.SilkS")
		)
		(fp_line
			(start 0.7874 -0.4064)
			(end 0.7874 0.4064)
			(stroke
				(width 0.1524)
				(type default)
			)
			(layer "F.SilkS")
		)
		(fp_line
			(start -0.67945 0.3048)
			(end -0.67945 -0.305054)
			(stroke
				(width 0.1)
				(type default)
			)
			(layer "F.Fab")
		)
		(fp_line
			(start -0.12065 0.3048)
			(end -0.67945 0.3048)
			(stroke
				(width 0.1)
				(type default)
			)
			(layer "F.Fab")
		)
		(fp_line
			(start 0.120396 0.3048)
			(end 0.120396 0.2794)
			(stroke
				(width 0.1)
				(type default)
			)
			(layer "F.Fab")
		)
		(fp_line
			(start 0.67945 0.3048)
			(end 0.120396 0.3048)
			(stroke
				(width 0.1)
				(type default)
			)
			(layer "F.Fab")
		)
		(fp_line
			(start -0.12065 0.2794)
			(end -0.12065 0.3048)
			(stroke
				(width 0.1)
				(type default)
			)
			(layer "F.Fab")
		)
		(fp_line
			(start 0.120396 0.2794)
			(end -0.12065 0.2794)
			(stroke
				(width 0.1)
				(type default)
			)
			(layer "F.Fab")
		)
		(fp_line
			(start -0.12065 -0.2794)
			(end 0.12065 -0.2794)
			(stroke
				(width 0.1)
				(type default)
			)
			(layer "F.Fab")
		)
		(fp_line
			(start 0.12065 -0.2794)
			(end 0.12065 -0.3048)
			(stroke
				(width 0.1)
				(type default)
			)
			(layer "F.Fab")
		)
		(fp_line
			(start 0.12065 -0.3048)
			(end 0.67945 -0.3048)
			(stroke
				(width 0.1)
				(type default)
			)
			(layer "F.Fab")
		)
		(fp_line
			(start 0.67945 -0.3048)
			(end 0.67945 0.3048)
			(stroke
				(width 0.1)
				(type default)
			)
			(layer "F.Fab")
		)
		(fp_line
			(start -0.67945 -0.305054)
			(end -0.12065 -0.305054)
			(stroke
				(width 0.1)
				(type default)
			)
			(layer "F.Fab")
		)
		(fp_line
			(start -0.12065 -0.305054)
			(end -0.12065 -0.2794)
			(stroke
				(width 0.1)
				(type default)
			)
			(layer "F.Fab")
		)
		(pad "1" smd circle
			(at -0.40005 0 270)
			(size 0 0)
			(layers "F.Cu" "F.Mask" "F.Paste")
			(net "P3V3_AUX")
		)
		(pad "2" smd circle
			(at 0.40005 0 270)
			(size 0 0)
			(layers "F.Cu" "F.Mask" "F.Paste")
			(net "RST_BMC_SRST_BUF_R_N")
		)
	)
	(footprint ""
		(layer "F.Cu")
		(at 68.072 -108.0262 90)
		(property "Reference" "R823"
			(at 0 0 90)
			(layer "F.SilkS")
			(hide yes)
			(effects
				(font
					(size 1.27 1.27)
				)
			)
		)
		(property "Value" ""
			(at 0 0 90)
			(layer "F.Fab")
			(effects
				(font
					(size 1.27 1.27)
				)
			)
		)
		(duplicate_pad_numbers_are_jumpers no)
		(fp_line
			(start 0.7874 -0.4064)
			(end 0.7874 0.4064)
			(stroke
				(width 0.1524)
				(type default)
			)
			(layer "F.SilkS")
		)
		(fp_line
			(start -0.7874 -0.4064)
			(end 0.7874 -0.4064)
			(stroke
				(width 0.1524)
				(type default)
			)
			(layer "F.SilkS")
		)
		(fp_line
			(start 0.7874 0.4064)
			(end -0.7874 0.4064)
			(stroke
				(width 0.1524)
				(type default)
			)
			(layer "F.SilkS")
		)
		(fp_line
			(start -0.7874 0.4064)
			(end -0.7874 -0.4064)
			(stroke
				(width 0.1524)
				(type default)
			)
			(layer "F.SilkS")
		)
		(fp_line
			(start -0.12065 -0.305054)
			(end -0.12065 -0.2794)
			(stroke
				(width 0.1)
				(type default)
			)
			(layer "F.Fab")
		)
		(fp_line
			(start -0.67945 -0.305054)
			(end -0.12065 -0.305054)
			(stroke
				(width 0.1)
				(type default)
			)
			(layer "F.Fab")
		)
		(fp_line
			(start 0.67945 -0.3048)
			(end 0.67945 0.3048)
			(stroke
				(width 0.1)
				(type default)
			)
			(layer "F.Fab")
		)
		(fp_line
			(start 0.12065 -0.3048)
			(end 0.67945 -0.3048)
			(stroke
				(width 0.1)
				(type default)
			)
			(layer "F.Fab")
		)
		(fp_line
			(start 0.12065 -0.2794)
			(end 0.12065 -0.3048)
			(stroke
				(width 0.1)
				(type default)
			)
			(layer "F.Fab")
		)
		(fp_line
			(start -0.12065 -0.2794)
			(end 0.12065 -0.2794)
			(stroke
				(width 0.1)
				(type default)
			)
			(layer "F.Fab")
		)
		(fp_line
			(start 0.120396 0.2794)
			(end -0.12065 0.2794)
			(stroke
				(width 0.1)
				(type default)
			)
			(layer "F.Fab")
		)
		(fp_line
			(start -0.12065 0.2794)
			(end -0.12065 0.3048)
			(stroke
				(width 0.1)
				(type default)
			)
			(layer "F.Fab")
		)
		(fp_line
			(start 0.67945 0.3048)
			(end 0.120396 0.3048)
			(stroke
				(width 0.1)
				(type default)
			)
			(layer "F.Fab")
		)
		(fp_line
			(start 0.120396 0.3048)
			(end 0.120396 0.2794)
			(stroke
				(width 0.1)
				(type default)
			)
			(layer "F.Fab")
		)
		(fp_line
			(start -0.12065 0.3048)
			(end -0.67945 0.3048)
			(stroke
				(width 0.1)
				(type default)
			)
			(layer "F.Fab")
		)
		(fp_line
			(start -0.67945 0.3048)
			(end -0.67945 -0.305054)
			(stroke
				(width 0.1)
				(type default)
			)
			(layer "F.Fab")
		)
		(pad "1" smd circle
			(at -0.40005 0 90)
			(size 0 0)
			(layers "F.Cu" "F.Mask" "F.Paste")
			(net "GND")
		)
		(pad "2" smd circle
			(at 0.40005 0 90)
			(size 0 0)
			(layers "F.Cu" "F.Mask" "F.Paste")
			(net "FM_VIRTUAL_RESEAT")
		)
	)
)
